# T6G (Grand Teton) — schematic netlist excerpt (pin names and nets, part order shuffled) for the footprints in the layout excerpt that follows; sources: Cadence DE-HDL packaged netlist, KiCad conversion of 04192023_DAF0TMB3IC0_F0TG_MB_C_brd_V02_OCP.brd

PU35  ISL99390FRZTR5935  ISL99390FRZ-TR5935 IC  pkg QFN21_6X5XB  page 218
  VOS  = PVDDCR_CPU1_P1_VOS1
  AGND  = GND
  VCC  = PVDDCR_CPU1_P1_VCC1
  PVCC  = PVDDCR_CPU1_P1_PVCC
  PGND1  = GND
  GL1  = NC_PVDDCR_CPU1_P1_GL1_1
  PGND2  = GND
  SW  = SW_PVDDCR_CPU1_P1_SW1
  VIN1  = SW_P12V_AUX_PVDDCR_CPU1_P1_FLT
  VIN2  = SW_P12V_AUX_PVDDCR_CPU1_P1_FLT
  DNC  = NC_PVDDCR_CPU1_P1_DNC1
  PHASE  = SW_PVDDCR_CPU1_P1_BOOTR1
  BOOT  = SW_PVDDCR_CPU1_P1_BOOT1
  PWM  = PVDDCR_CPU1_P1_PWM1
  EN  = PVDDCR_CPU1_P1_VCC1
  TOUT_FLT  = PVDDCR_CPU1_P1_TEMP0
  LSET  = PVDDCR_CPU1_P1_LSET1
  IOUT  = PVDDCR_CPU1_P1_IMON1
  REFIN  = PVDDCR_CPU1_P1_VCCS
  PGND3  = GND
  GL2  = NC_PVDDCR_CPU1_P1_GL2_1

(kicad_pcb
	(version 20260206)
	(generator "pcbnew")
	(generator_version "10.0")
	(general
		(thickness 1.6)
		(legacy_teardrops no)
	)
	(paper "A4")
	(title_block
		(title "04192023_DAF0TMB3IC0_F0TG_MB_C_brd_V02_OCP.brd")
		(comment 1 "Grand Teton / footprints 2889-2889 of 8354")
	)
	(layers
		(0 "F.Cu" signal "TOP")
		(4 "In1.Cu" signal "GND")
		(6 "In2.Cu" signal "IN1")
		(8 "In3.Cu" signal "GND1")
		(10 "In4.Cu" signal "IN2")
		(12 "In5.Cu" signal "GND2")
		(14 "In6.Cu" signal "IN3")
		(16 "In7.Cu" signal "GND3")
		(18 "In8.Cu" signal "VCC")
		(20 "In9.Cu" signal "VCC1")
		(22 "In10.Cu" signal "GND4")
		(24 "In11.Cu" signal "IN4")
		(26 "In12.Cu" signal "GND5")
		(28 "In13.Cu" signal "IN5")
		(30 "In14.Cu" signal "GND6")
		(32 "In15.Cu" signal "IN6")
		(34 "In16.Cu" signal "GND7")
		(2 "B.Cu" signal "BOTTOM")
		(9 "F.Adhes" user "F.Adhesive")
		(11 "B.Adhes" user "B.Adhesive")
		(13 "F.Paste" user "Package Geometry/Pastemask Top")
		(15 "B.Paste" user "Package Geometry/Pastemask Bottom")
		(5 "F.SilkS" user "Ref Des/Silkscreen Top")
		(7 "B.SilkS" user "Ref Des/Silkscreen Bottom")
		(1 "F.Mask" user "Board Geometry/Soldermask Top")
		(3 "B.Mask" user "Board Geometry/Soldermask Bottom")
		(17 "Dwgs.User" user "User.Drawings")
		(19 "Cmts.User" user "User.Comments")
		(21 "Eco1.User" user "User.Eco1")
		(23 "Eco2.User" user "User.Eco2")
		(25 "Edge.Cuts" user "Board Geometry/Outline")
		(27 "Margin" user)
		(31 "F.CrtYd" user "Package Geometry/Place Bound Top")
		(29 "B.CrtYd" user "Package Geometry/Place Bound Bottom")
		(35 "F.Fab" user "Ref Des/Assembly Top")
		(33 "B.Fab" user "Ref Des/Assembly Bottom")
	)
	(footprint ""
		(layer "F.Cu")
		(at 87.122254 -334.978502)
		(property "Reference" "PU35"
			(at -3.048254 -8.529828 0)
			(unlocked yes)
			(layer "F.SilkS")
			(effects
				(font
					(size 0.7874 0.5842)
					(thickness 0.1524)
				)
				(justify left)
			)
		)
		(property "Value" ""
			(at 0 0 0)
			(layer "F.Fab")
			(effects
				(font
					(size 1.27 1.27)
				)
			)
		)
		(duplicate_pad_numbers_are_jumpers no)
		(fp_line
			(start -2.500122 -2.999994)
			(end -2.24409 -2.999994)
			(stroke
				(width 0.1524)
				(type default)
			)
			(layer "F.SilkS")
		)
		(fp_line
			(start -2.500122 -2.529078)
			(end -2.500122 -2.999994)
			(stroke
				(width 0.1524)
				(type default)
			)
			(layer "F.SilkS")
		)
		(fp_line
			(start -2.500122 0.6604)
			(end -2.500122 0.229108)
			(stroke
				(width 0.1524)
				(type default)
			)
			(layer "F.SilkS")
		)
		(fp_line
			(start -2.500122 2.999994)
			(end -2.500122 2.339594)
			(stroke
				(width 0.1524)
				(type default)
			)
			(layer "F.SilkS")
		)
		(fp_line
			(start -2.2987 2.999994)
			(end -2.500122 2.999994)
			(stroke
				(width 0.1524)
				(type default)
			)
			(layer "F.SilkS")
		)
		(fp_line
			(start 2.31394 -2.999994)
			(end 2.500122 -2.999994)
			(stroke
				(width 0.1524)
				(type default)
			)
			(layer "F.SilkS")
		)
		(fp_line
			(start 2.500122 -2.999994)
			(end 2.500122 -2.44348)
			(stroke
				(width 0.1524)
				(type default)
			)
			(layer "F.SilkS")
		)
		(fp_line
			(start 2.500122 2.339594)
			(end 2.500122 2.999994)
			(stroke
				(width 0.1524)
				(type default)
			)
			(layer "F.SilkS")
		)
		(fp_line
			(start 2.500122 2.999994)
			(end 2.2987 2.999994)
			(stroke
				(width 0.1524)
				(type default)
			)
			(layer "F.SilkS")
		)
		(fp_poly
			(pts
				(xy -2.737612 -2.387092) (xy -3.410966 -2.611628) (xy -2.962148 -3.0607)
			)
			(stroke
				(width 0)
				(type default)
			)
			(fill yes)
			(layer "F.SilkS")
		)
		(fp_line
			(start -2.500122 -2.999994)
			(end 2.500122 -2.999994)
			(stroke
				(width 0.1)
				(type default)
			)
			(layer "F.Fab")
		)
		(fp_line
			(start -2.500122 2.999994)
			(end -2.500122 -2.999994)
			(stroke
				(width 0.1)
				(type default)
			)
			(layer "F.Fab")
		)
		(fp_line
			(start 2.500122 -2.999994)
			(end 2.500122 2.999994)
			(stroke
				(width 0.1)
				(type default)
			)
			(layer "F.Fab")
		)
		(fp_line
			(start 2.500122 2.999994)
			(end -2.500122 2.999994)
			(stroke
				(width 0.1)
				(type default)
			)
			(layer "F.Fab")
		)
		(fp_poly
			(pts
				(xy -4.218432 -2.783078) (xy -4.218432 -1.767078) (xy -3.202432 -2.275078)
			)
			(stroke
				(width 0)
				(type default)
			)
			(fill yes)
			(layer "F.Fab")
		)
		(pad "1" smd rect
			(at -2.400046 -2.275078 90)
			(size 0.2286 0.6096)
			(layers "F.Cu" "F.Mask" "F.Paste")
			(net "PVDDCR_CPU1_P1_VOS1")
		)
		(pad "2" smd rect
			(at -2.400046 -1.82499 90)
			(size 0.2286 0.6096)
			(layers "F.Cu" "F.Mask" "F.Paste")
			(net "GND")
		)
		(pad "3" smd rect
			(at -2.400046 -1.374902 90)
			(size 0.2286 0.6096)
			(layers "F.Cu" "F.Mask" "F.Paste")
			(net "PVDDCR_CPU1_P1_VCC1")
		)
		(pad "4" smd rect
			(at -2.400046 -0.925068 90)
			(size 0.2286 0.6096)
			(layers "F.Cu" "F.Mask" "F.Paste")
			(net "PVDDCR_CPU1_P1_PVCC")
		)
		(pad "5" smd rect
			(at -2.400046 -0.47498 90)
			(size 0.2286 0.6096)
			(layers "F.Cu" "F.Mask" "F.Paste")
			(net "GND")
		)
		(pad "6" smd rect
			(at -2.400046 -0.024892 90)
			(size 0.2286 0.6096)
			(layers "F.Cu" "F.Mask" "F.Paste")
			(net "NC_PVDDCR_CPU1_P1_GL1_1")
		)
		(pad "7_9-20_24" smd circle
			(at 0 1.150112 90)
			(size 0 0)
			(layers "F.Cu" "F.Mask" "F.Paste")
			(net "GND")
		)
		(pad "10_19" smd rect
			(at 0 2.899918 90)
			(size 0.6096 4.318)
			(layers "F.Cu" "F.Mask" "F.Paste")
			(net "SW_PVDDCR_CPU1_P1_SW1")
		)
		(pad "25_29" smd rect
			(at 1.549908 -1.279906 270)
			(size 2.0574 2.3114)
			(layers "F.Cu" "F.Mask" "F.Paste")
			(net "SW_P12V_AUX_PVDDCR_CPU1_P1_FLT")
		)
		(pad "30" smd rect
			(at 2.05994 -2.899918)
			(size 0.2286 0.6096)
			(layers "F.Cu" "F.Mask" "F.Paste")
			(net "SW_P12V_AUX_PVDDCR_CPU1_P1_FLT")
		)
		(pad "31" smd rect
			(at 1.610106 -2.899918)
			(size 0.2286 0.6096)
			(layers "F.Cu" "F.Mask" "F.Paste")
			(net "NC_PVDDCR_CPU1_P1_DNC1")
		)
		(pad "32" smd rect
			(at 1.160018 -2.899918)
			(size 0.2286 0.6096)
			(layers "F.Cu" "F.Mask" "F.Paste")
			(net "SW_PVDDCR_CPU1_P1_BOOTR1")
		)
		(pad "33" smd rect
			(at 0.70993 -2.899918)
			(size 0.2286 0.6096)
			(layers "F.Cu" "F.Mask" "F.Paste")
			(net "SW_PVDDCR_CPU1_P1_BOOT1")
		)
		(pad "34" smd rect
			(at 0.260096 -2.899918)
			(size 0.2286 0.6096)
			(layers "F.Cu" "F.Mask" "F.Paste")
			(net "PVDDCR_CPU1_P1_PWM1")
		)
		(pad "35" smd rect
			(at -0.189992 -2.899918)
			(size 0.2286 0.6096)
			(layers "F.Cu" "F.Mask" "F.Paste")
			(net "PVDDCR_CPU1_P1_VCC1")
		)
		(pad "36" smd rect
			(at -0.64008 -2.899918)
			(size 0.2286 0.6096)
			(layers "F.Cu" "F.Mask" "F.Paste")
			(net "PVDDCR_CPU1_P1_TEMP0")
		)
		(pad "37" smd rect
			(at -1.089914 -2.899918)
			(size 0.2286 0.6096)
			(layers "F.Cu" "F.Mask" "F.Paste")
			(net "PVDDCR_CPU1_P1_LSET1")
		)
		(pad "38" smd rect
			(at -1.540002 -2.899918)
			(size 0.2286 0.6096)
			(layers "F.Cu" "F.Mask" "F.Paste")
			(net "PVDDCR_CPU1_P1_IMON1")
		)
		(pad "39" smd rect
			(at -1.99009 -2.899918)
			(size 0.2286 0.6096)
			(layers "F.Cu" "F.Mask" "F.Paste")
			(net "PVDDCR_CPU1_P1_VCCS")
		)
		(pad "40" smd rect
			(at -0.87503 -1.27508)
			(size 1.7526 1.9558)
			(layers "F.Cu" "F.Mask" "F.Paste")
			(net "GND")
		)
		(pad "41" smd rect
			(at -1.525016 0.249936 270)
			(size 0.3048 0.4572)
			(layers "F.Cu" "F.Mask" "F.Paste")
			(net "NC_PVDDCR_CPU1_P1_GL2_1")
		)
		(zone
			(layer "F.Cu")
			(hatch none 0.5)
			(connect_pads
				(clearance 0)
			)
			(min_thickness 0.25)
			(keepout
				(tracks not_allowed)
				(vias allowed)
				(pads allowed)
				(copperpour not_allowed)
				(footprints allowed)
			)
			(placement
				(enabled no)
				(sheetname "")
			)
			(fill
				(thermal_gap 0.5)
				(thermal_bridge_width 0.5)
				(island_removal_mode 0)
			)
			(polygon
				(pts
					(xy 84.622132 -332.40599) (xy 84.622132 -332.727808) (xy 89.622376 -332.727808) (xy 89.622376 -332.394306)
					(xy 89.332054 -332.394306) (xy 89.332054 -332.434184) (xy 84.912454 -332.434184) (xy 84.912454 -332.40599)
				)
			)
		)
		(zone
			(layer "F.Cu")
			(hatch none 0.5)
			(connect_pads
				(clearance 0)
			)
			(min_thickness 0.25)
			(keepout
				(tracks not_allowed)
				(vias allowed)
				(pads allowed)
				(copperpour not_allowed)
				(footprints allowed)
			)
			(placement
				(enabled no)
				(sheetname "")
			)
			(fill
				(thermal_gap 0.5)
				(thermal_bridge_width 0.5)
				(island_removal_mode 0)
			)
			(polygon
				(pts
					(xy 87.174324 -335.224882) (xy 87.174324 -337.282282) (xy 85.320124 -337.282282) (xy 85.320124 -337.041236)
					(xy 85.077808 -337.041236) (xy 85.077808 -337.52282) (xy 88.87587 -337.52282) (xy 88.87587 -337.337908)
					(xy 87.465662 -337.337908) (xy 87.465662 -335.178908) (xy 89.622376 -335.178908) (xy 89.622376 -334.929226)
					(xy 87.46998 -334.929226)
				)
			)
		)
	)
)
